# T6G (Grand Teton) — schematic parts with pin connectivity, parts 2655–2657 of 8303; source: Cadence DE-HDL packaged netlist (pstxprt.dat, pstxnet.dat, pstchip.dat)

J109  CONN112_10137002101LF  CONN112_10137002-101LF IO  pkg HSD_F112D8_P2W1-2_RDH  page 119
  A1  A1  BI  = BMC_MONITER_BUF
  A2  A2  BI  = GND
  A3  A3  BI  = BIC_MONITER
  A4  A4  BI  = GND
  A5  A5  BI  = SMB_BMC_SWB_BUF_SCL
  A6  A6  BI  = GND
  A7  A7  BI  = SMB_BMC_SWB_BUF_SDA
  A8  A8  BI  = GND
  B1  B1  BI  = GND
  B2  B2  BI  = P5E_CPU1_P2_RX_BUF_DN<9>
  B3  B3  BI  = GND
  B4  B4  BI  = P5E_CPU1_P2_RX_BUF_DN<11>
  B5  B5  BI  = GND
  B6  B6  BI  = P5E_CPU1_P2_RX_BUF_DN<13>
  B7  B7  BI  = GND
  B8  B8  BI  = P5E_CPU1_P2_RX_BUF_DN<15>
  C1  C1  BI  = P5E_CPU1_P2_RX_BUF_DN<8>
  C2  C2  BI  = P5E_CPU1_P2_RX_BUF_DP<9>
  C3  C3  BI  = P5E_CPU1_P2_RX_BUF_DN<10>
  C4  C4  BI  = P5E_CPU1_P2_RX_BUF_DP<11>
  C5  C5  BI  = P5E_CPU1_P2_RX_BUF_DN<12>
  C6  C6  BI  = P5E_CPU1_P2_RX_BUF_DP<13>
  C7  C7  BI  = P5E_CPU1_P2_RX_BUF_DN<14>
  C8  C8  BI  = P5E_CPU1_P2_RX_BUF_DP<15>
  D1  D1  BI  = P5E_CPU1_P2_RX_BUF_DP<8>
  D2  D2  BI  = GND
  D3  D3  BI  = P5E_CPU1_P2_RX_BUF_DP<10>
  D4  D4  BI  = GND
  D5  D5  BI  = P5E_CPU1_P2_RX_BUF_DP<12>
  D6  D6  BI  = GND
  D7  D7  BI  = P5E_CPU1_P2_RX_BUF_DP<14>
  D8  D8  BI  = GND
  E1  E1  BI  = GND
  E2  E2  BI  = P5E_CPU1_P3_RX_BUF_DN<9>
  E3  E3  BI  = GND
  E4  E4  BI  = P5E_CPU1_P3_RX_BUF_DN<11>
  E5  E5  BI  = GND
  E6  E6  BI  = P5E_CPU1_P3_RX_BUF_DN<13>
  E7  E7  BI  = GND
  E8  E8  BI  = P5E_CPU1_P3_RX_BUF_DN<15>
  F1  F1  BI  = P5E_CPU1_P3_RX_BUF_DN<8>
  F2  F2  BI  = P5E_CPU1_P3_RX_BUF_DP<9>
  F3  F3  BI  = P5E_CPU1_P3_RX_BUF_DN<10>
  F4  F4  BI  = P5E_CPU1_P3_RX_BUF_DP<11>
  F5  F5  BI  = P5E_CPU1_P3_RX_BUF_DN<12>
  F6  F6  BI  = P5E_CPU1_P3_RX_BUF_DP<13>
  F7  F7  BI  = P5E_CPU1_P3_RX_BUF_DN<14>
  F8  F8  BI  = P5E_CPU1_P3_RX_BUF_DP<15>
  G1  G1  BI  = P5E_CPU1_P3_RX_BUF_DP<8>
  G2  G2  BI  = GND
  G3  G3  BI  = P5E_CPU1_P3_RX_BUF_DP<10>
  G4  G4  BI  = GND
  G5  G5  BI  = P5E_CPU1_P3_RX_BUF_DP<12>
  G6  G6  BI  = GND
  G7  G7  BI  = P5E_CPU1_P3_RX_BUF_DP<14>
  G8  G8  BI  = GND
  H1  H1  BI  = GND
  H2  H2  BI  = P5E_CPU1_P2_TX_BUF_C_DN<9>
  H3  H3  BI  = GND
  H4  H4  BI  = P5E_CPU1_P2_TX_BUF_C_DN<11>
  H5  H5  BI  = GND
  H6  H6  BI  = P5E_CPU1_P2_TX_BUF_C_DN<13>
  H7  H7  BI  = GND
  H8  H8  BI  = P5E_CPU1_P2_TX_BUF_C_DN<15>
  I1  I1  BI  = P5E_CPU1_P2_TX_BUF_C_DN<8>
  I2  I2  BI  = P5E_CPU1_P2_TX_BUF_C_DP<9>
  I3  I3  BI  = P5E_CPU1_P2_TX_BUF_C_DN<10>
  I4  I4  BI  = P5E_CPU1_P2_TX_BUF_C_DP<11>
  I5  I5  BI  = P5E_CPU1_P2_TX_BUF_C_DN<12>
  I6  I6  BI  = P5E_CPU1_P2_TX_BUF_C_DP<13>
  I7  I7  BI  = P5E_CPU1_P2_TX_BUF_C_DN<14>
  I8  I8  BI  = P5E_CPU1_P2_TX_BUF_C_DP<15>
  J1  J1  BI  = P5E_CPU1_P2_TX_BUF_C_DP<8>
  J2  J2  BI  = GND
  J3  J3  BI  = P5E_CPU1_P2_TX_BUF_C_DP<10>
  J4  J4  BI  = GND
  J5  J5  BI  = P5E_CPU1_P2_TX_BUF_C_DP<12>
  J6  J6  BI  = GND
  J7  J7  BI  = P5E_CPU1_P2_TX_BUF_C_DP<14>
  J8  J8  BI  = GND
  K1  K1  BI  = GND
  K2  K2  BI  = P5E_CPU1_P3_TX_BUF_C_DN<9>
  K3  K3  BI  = GND
  K4  K4  BI  = P5E_CPU1_P3_TX_BUF_C_DN<11>
  K5  K5  BI  = GND
  K6  K6  BI  = P5E_CPU1_P3_TX_BUF_C_DN<13>
  K7  K7  BI  = GND
  K8  K8  BI  = P5E_CPU1_P3_TX_BUF_C_DN<15>
  L1  L1  BI  = P5E_CPU1_P3_TX_BUF_C_DN<8>
  L2  L2  BI  = P5E_CPU1_P3_TX_BUF_C_DP<9>
  L3  L3  BI  = P5E_CPU1_P3_TX_BUF_C_DN<10>
  L4  L4  BI  = P5E_CPU1_P3_TX_BUF_C_DP<11>
  L5  L5  BI  = P5E_CPU1_P3_TX_BUF_C_DN<12>
  L6  L6  BI  = P5E_CPU1_P3_TX_BUF_C_DP<13>
  L7  L7  BI  = P5E_CPU1_P3_TX_BUF_C_DN<14>
  L8  L8  BI  = P5E_CPU1_P3_TX_BUF_C_DP<15>
  M1  M1  BI  = P5E_CPU1_P3_TX_BUF_C_DP<8>
  M2  M2  BI  = GND
  M3  M3  BI  = P5E_CPU1_P3_TX_BUF_C_DP<10>
  M4  M4  BI  = GND
  M5  M5  BI  = P5E_CPU1_P3_TX_BUF_C_DP<12>
  M6  M6  BI  = GND
  M7  M7  BI  = P5E_CPU1_P3_TX_BUF_C_DP<14>
  M8  M8  BI  = GND
  N1  N1  BI  = GND
  N2  N2  BI  = GPU_FPGA_EROT_FATALERR_N
  N3  N3  BI  = GND
  N4  N4  BI  = GPU_3V3IO_RSVD0_FFU
  N5  N5  BI  = GND
  N6  N6  BI  = GPU_3V3IO_RSVD1_FFU
  N7  N7  BI  = GND
  N8  N8  BI  = PRSNT_CABLE_GPU_B3_N

J110  CONN112_10137002101LF  CONN112_10137002-101LF IO  pkg HSD_F112D8_P2W1-2_RDH  page 120
  A1  A1  BI  = GPU_FPGA_EROT_RECOV_BUF_N
  A2  A2  BI  = GND
  A3  A3  BI  = GPU_HMC_PRSNT_N
  A4  A4  BI  = GND
  A5  A5  BI  = GPU_BASE_HMC_READY
  A6  A6  BI  = GND
  A7  A7  BI  = GPU_BASE_STBY_EN_BUF
  A8  A8  BI  = GND
  B1  B1  BI  = GND
  B2  B2  BI  = P5E_CPU1_P2_RX_BUF_DN<1>
  B3  B3  BI  = GND
  B4  B4  BI  = P5E_CPU1_P2_RX_BUF_DN<3>
  B5  B5  BI  = GND
  B6  B6  BI  = P5E_CPU1_P2_RX_BUF_DN<5>
  B7  B7  BI  = GND
  B8  B8  BI  = P5E_CPU1_P2_RX_BUF_DN<7>
  C1  C1  BI  = P5E_CPU1_P2_RX_BUF_DN<0>
  C2  C2  BI  = P5E_CPU1_P2_RX_BUF_DP<1>
  C3  C3  BI  = P5E_CPU1_P2_RX_BUF_DN<2>
  C4  C4  BI  = P5E_CPU1_P2_RX_BUF_DP<3>
  C5  C5  BI  = P5E_CPU1_P2_RX_BUF_DN<4>
  C6  C6  BI  = P5E_CPU1_P2_RX_BUF_DP<5>
  C7  C7  BI  = P5E_CPU1_P2_RX_BUF_DN<6>
  C8  C8  BI  = P5E_CPU1_P2_RX_BUF_DP<7>
  D1  D1  BI  = P5E_CPU1_P2_RX_BUF_DP<0>
  D2  D2  BI  = GND
  D3  D3  BI  = P5E_CPU1_P2_RX_BUF_DP<2>
  D4  D4  BI  = GND
  D5  D5  BI  = P5E_CPU1_P2_RX_BUF_DP<4>
  D6  D6  BI  = GND
  D7  D7  BI  = P5E_CPU1_P2_RX_BUF_DP<6>
  D8  D8  BI  = GND
  E1  E1  BI  = GND
  E2  E2  BI  = P5E_CPU1_P3_RX_BUF_DN<1>
  E3  E3  BI  = GND
  E4  E4  BI  = P5E_CPU1_P3_RX_BUF_DN<3>
  E5  E5  BI  = GND
  E6  E6  BI  = P5E_CPU1_P3_RX_BUF_DN<5>
  E7  E7  BI  = GND
  E8  E8  BI  = P5E_CPU1_P3_RX_BUF_DN<7>
  F1  F1  BI  = P5E_CPU1_P3_RX_BUF_DN<0>
  F2  F2  BI  = P5E_CPU1_P3_RX_BUF_DP<1>
  F3  F3  BI  = P5E_CPU1_P3_RX_BUF_DN<2>
  F4  F4  BI  = P5E_CPU1_P3_RX_BUF_DP<3>
  F5  F5  BI  = P5E_CPU1_P3_RX_BUF_DN<4>
  F6  F6  BI  = P5E_CPU1_P3_RX_BUF_DP<5>
  F7  F7  BI  = P5E_CPU1_P3_RX_BUF_DN<6>
  F8  F8  BI  = P5E_CPU1_P3_RX_BUF_DP<7>
  G1  G1  BI  = P5E_CPU1_P3_RX_BUF_DP<0>
  G2  G2  BI  = GND
  G3  G3  BI  = P5E_CPU1_P3_RX_BUF_DP<2>
  G4  G4  BI  = GND
  G5  G5  BI  = P5E_CPU1_P3_RX_BUF_DP<4>
  G6  G6  BI  = GND
  G7  G7  BI  = P5E_CPU1_P3_RX_BUF_DP<6>
  G8  G8  BI  = GND
  H1  H1  BI  = GND
  H2  H2  BI  = P5E_CPU1_P2_TX_BUF_C_DN<1>
  H3  H3  BI  = GND
  H4  H4  BI  = P5E_CPU1_P2_TX_BUF_C_DN<3>
  H5  H5  BI  = GND
  H6  H6  BI  = P5E_CPU1_P2_TX_BUF_C_DN<5>
  H7  H7  BI  = GND
  H8  H8  BI  = P5E_CPU1_P2_TX_BUF_C_DN<7>
  I1  I1  BI  = P5E_CPU1_P2_TX_BUF_C_DN<0>
  I2  I2  BI  = P5E_CPU1_P2_TX_BUF_C_DP<1>
  I3  I3  BI  = P5E_CPU1_P2_TX_BUF_C_DN<2>
  I4  I4  BI  = P5E_CPU1_P2_TX_BUF_C_DP<3>
  I5  I5  BI  = P5E_CPU1_P2_TX_BUF_C_DN<4>
  I6  I6  BI  = P5E_CPU1_P2_TX_BUF_C_DP<5>
  I7  I7  BI  = P5E_CPU1_P2_TX_BUF_C_DN<6>
  I8  I8  BI  = P5E_CPU1_P2_TX_BUF_C_DP<7>
  J1  J1  BI  = P5E_CPU1_P2_TX_BUF_C_DP<0>
  J2  J2  BI  = GND
  J3  J3  BI  = P5E_CPU1_P2_TX_BUF_C_DP<2>
  J4  J4  BI  = GND
  J5  J5  BI  = P5E_CPU1_P2_TX_BUF_C_DP<4>
  J6  J6  BI  = GND
  J7  J7  BI  = P5E_CPU1_P2_TX_BUF_C_DP<6>
  J8  J8  BI  = GND
  K1  K1  BI  = GND
  K2  K2  BI  = P5E_CPU1_P3_TX_BUF_C_DN<1>
  K3  K3  BI  = GND
  K4  K4  BI  = P5E_CPU1_P3_TX_BUF_C_DN<3>
  K5  K5  BI  = GND
  K6  K6  BI  = P5E_CPU1_P3_TX_BUF_C_DN<5>
  K7  K7  BI  = GND
  K8  K8  BI  = P5E_CPU1_P3_TX_BUF_C_DN<7>
  L1  L1  BI  = P5E_CPU1_P3_TX_BUF_C_DN<0>
  L2  L2  BI  = P5E_CPU1_P3_TX_BUF_C_DP<1>
  L3  L3  BI  = P5E_CPU1_P3_TX_BUF_C_DN<2>
  L4  L4  BI  = P5E_CPU1_P3_TX_BUF_C_DP<3>
  L5  L5  BI  = P5E_CPU1_P3_TX_BUF_C_DN<4>
  L6  L6  BI  = P5E_CPU1_P3_TX_BUF_C_DP<5>
  L7  L7  BI  = P5E_CPU1_P3_TX_BUF_C_DN<6>
  L8  L8  BI  = P5E_CPU1_P3_TX_BUF_C_DP<7>
  M1  M1  BI  = P5E_CPU1_P3_TX_BUF_C_DP<0>
  M2  M2  BI  = GND
  M3  M3  BI  = P5E_CPU1_P3_TX_BUF_C_DP<2>
  M4  M4  BI  = GND
  M5  M5  BI  = P5E_CPU1_P3_TX_BUF_C_DP<4>
  M6  M6  BI  = GND
  M7  M7  BI  = P5E_CPU1_P3_TX_BUF_C_DP<6>
  M8  M8  BI  = GND
  N1  N1  BI  = GND
  N2  N2  BI  = GPU_FPGA_BOOT_EN_BUF
  N3  N3  BI  = GND
  N4  N4  BI  = FM_SMB_1_ALERT_GPU_N
  N5  N5  BI  = GND
  N6  N6  BI  = FM_SMB_2_ALERT_GPU_N
  N7  N7  BI  = GND
  N8  N8  BI  = GPU_FPGA_EROT_RST_BUF_N

J111  CONN112_10137002101LF  CONN112_10137002-101LF IO  pkg HSD_F112D8_P2W1-2_RDH  page 121
  A1  A1  BI  = GPU_PEX_STRAP1
  A2  A2  BI  = GND
  A3  A3  BI  = GPU_BASE_ID0
  A4  A4  BI  = GND
  A5  A5  BI  = GPU_PEX_STRAP0
  A6  A6  BI  = GND
  A7  A7  BI  = GPU_FPGA_RST_R_BUF_N
  A8  A8  BI  = GND
  B1  B1  BI  = GND
  B2  B2  BI  = P5E_CPU1_P0_RX_BUF_DN<9>
  B3  B3  BI  = GND
  B4  B4  BI  = P5E_CPU1_P0_RX_BUF_DN<11>
  B5  B5  BI  = GND
  B6  B6  BI  = P5E_CPU1_P0_RX_BUF_DN<13>
  B7  B7  BI  = GND
  B8  B8  BI  = P5E_CPU1_P0_RX_BUF_DN<15>
  C1  C1  BI  = P5E_CPU1_P0_RX_BUF_DN<8>
  C2  C2  BI  = P5E_CPU1_P0_RX_BUF_DP<9>
  C3  C3  BI  = P5E_CPU1_P0_RX_BUF_DN<10>
  C4  C4  BI  = P5E_CPU1_P0_RX_BUF_DP<11>
  C5  C5  BI  = P5E_CPU1_P0_RX_BUF_DN<12>
  C6  C6  BI  = P5E_CPU1_P0_RX_BUF_DP<13>
  C7  C7  BI  = P5E_CPU1_P0_RX_BUF_DN<14>
  C8  C8  BI  = P5E_CPU1_P0_RX_BUF_DP<15>
  D1  D1  BI  = P5E_CPU1_P0_RX_BUF_DP<8>
  D2  D2  BI  = GND
  D3  D3  BI  = P5E_CPU1_P0_RX_BUF_DP<10>
  D4  D4  BI  = GND
  D5  D5  BI  = P5E_CPU1_P0_RX_BUF_DP<12>
  D6  D6  BI  = GND
  D7  D7  BI  = P5E_CPU1_P0_RX_BUF_DP<14>
  D8  D8  BI  = GND
  E1  E1  BI  = GND
  E2  E2  BI  = P5E_CPU1_P1_RX_BUF_DN<9>
  E3  E3  BI  = GND
  E4  E4  BI  = P5E_CPU1_P1_RX_BUF_DN<11>
  E5  E5  BI  = GND
  E6  E6  BI  = P5E_CPU1_P1_RX_BUF_DN<13>
  E7  E7  BI  = GND
  E8  E8  BI  = P5E_CPU1_P1_RX_BUF_DN<15>
  F1  F1  BI  = P5E_CPU1_P1_RX_BUF_DN<8>
  F2  F2  BI  = P5E_CPU1_P1_RX_BUF_DP<9>
  F3  F3  BI  = P5E_CPU1_P1_RX_BUF_DN<10>
  F4  F4  BI  = P5E_CPU1_P1_RX_BUF_DP<11>
  F5  F5  BI  = P5E_CPU1_P1_RX_BUF_DN<12>
  F6  F6  BI  = P5E_CPU1_P1_RX_BUF_DP<13>
  F7  F7  BI  = P5E_CPU1_P1_RX_BUF_DN<14>
  F8  F8  BI  = P5E_CPU1_P1_RX_BUF_DP<15>
  G1  G1  BI  = P5E_CPU1_P1_RX_BUF_DP<8>
  G2  G2  BI  = GND
  G3  G3  BI  = P5E_CPU1_P1_RX_BUF_DP<10>
  G4  G4  BI  = GND
  G5  G5  BI  = P5E_CPU1_P1_RX_BUF_DP<12>
  G6  G6  BI  = GND
  G7  G7  BI  = P5E_CPU1_P1_RX_BUF_DP<14>
  G8  G8  BI  = GND
  H1  H1  BI  = GND
  H2  H2  BI  = P5E_CPU1_P0_TX_BUF_C_DN<9>
  H3  H3  BI  = GND
  H4  H4  BI  = P5E_CPU1_P0_TX_BUF_C_DN<11>
  H5  H5  BI  = GND
  H6  H6  BI  = P5E_CPU1_P0_TX_BUF_C_DN<13>
  H7  H7  BI  = GND
  H8  H8  BI  = P5E_CPU1_P0_TX_BUF_C_DN<15>
  I1  I1  BI  = P5E_CPU1_P0_TX_BUF_C_DN<8>
  I2  I2  BI  = P5E_CPU1_P0_TX_BUF_C_DP<9>
  I3  I3  BI  = P5E_CPU1_P0_TX_BUF_C_DN<10>
  I4  I4  BI  = P5E_CPU1_P0_TX_BUF_C_DP<11>
  I5  I5  BI  = P5E_CPU1_P0_TX_BUF_C_DN<12>
  I6  I6  BI  = P5E_CPU1_P0_TX_BUF_C_DP<13>
  I7  I7  BI  = P5E_CPU1_P0_TX_BUF_C_DN<14>
  I8  I8  BI  = P5E_CPU1_P0_TX_BUF_C_DP<15>
  J1  J1  BI  = P5E_CPU1_P0_TX_BUF_C_DP<8>
  J2  J2  BI  = GND
  J3  J3  BI  = P5E_CPU1_P0_TX_BUF_C_DP<10>
  J4  J4  BI  = GND
  J5  J5  BI  = P5E_CPU1_P0_TX_BUF_C_DP<12>
  J6  J6  BI  = GND
  J7  J7  BI  = P5E_CPU1_P0_TX_BUF_C_DP<14>
  J8  J8  BI  = GND
  K1  K1  BI  = GND
  K2  K2  BI  = P5E_CPU1_P1_TX_BUF_C_DN<9>
  K3  K3  BI  = GND
  K4  K4  BI  = P5E_CPU1_P1_TX_BUF_C_DN<11>
  K5  K5  BI  = GND
  K6  K6  BI  = P5E_CPU1_P1_TX_BUF_C_DN<13>
  K7  K7  BI  = GND
  K8  K8  BI  = P5E_CPU1_P1_TX_BUF_C_DN<15>
  L1  L1  BI  = P5E_CPU1_P1_TX_BUF_C_DN<8>
  L2  L2  BI  = P5E_CPU1_P1_TX_BUF_C_DP<9>
  L3  L3  BI  = P5E_CPU1_P1_TX_BUF_C_DN<10>
  L4  L4  BI  = P5E_CPU1_P1_TX_BUF_C_DP<11>
  L5  L5  BI  = P5E_CPU1_P1_TX_BUF_C_DN<12>
  L6  L6  BI  = P5E_CPU1_P1_TX_BUF_C_DP<13>
  L7  L7  BI  = P5E_CPU1_P1_TX_BUF_C_DN<14>
  L8  L8  BI  = P5E_CPU1_P1_TX_BUF_C_DP<15>
  M1  M1  BI  = P5E_CPU1_P1_TX_BUF_C_DP<8>
  M2  M2  BI  = GND
  M3  M3  BI  = P5E_CPU1_P1_TX_BUF_C_DP<10>
  M4  M4  BI  = GND
  M5  M5  BI  = P5E_CPU1_P1_TX_BUF_C_DP<12>
  M6  M6  BI  = GND
  M7  M7  BI  = P5E_CPU1_P1_TX_BUF_C_DP<14>
  M8  M8  BI  = GND
  N1  N1  BI  = GND
  N2  N2  BI  = GPU_PRSNT_N
  N3  N3  BI  = GND
  N4  N4  BI  = FM_GPU_PWR_EN_R_BUF
  N5  N5  BI  = GND
  N6  N6  BI  = FM_GPU_PWRGD
  N7  N7  BI  = GND
  N8  N8  BI  = GPU_BASE_ID1
